(kicad_pcb
	(version 20260206)
	(generator "pcbnew")
	(generator_version "10.0")
	(general
		(thickness 1.6)
		(legacy_teardrops no)
	)
	(paper "A4")
	(title_block
		(title "Bryce Canyon_R.DPB_16317-1_OCP.brd")
		(comment 1 "Bryce Canyon / footprints 174-180 of 2099")
	)
	(layers
		(0 "F.Cu" signal "TOP")
		(4 "In1.Cu" signal "L2GND")
		(6 "In2.Cu" signal "L3")
		(8 "In3.Cu" signal "L4VCC")
		(10 "In4.Cu" signal "L5VCC")
		(12 "In5.Cu" signal "L6")
		(14 "In6.Cu" signal "L7GND")
		(2 "B.Cu" signal "BOTTOM")
		(9 "F.Adhes" user "F.Adhesive")
		(11 "B.Adhes" user "B.Adhesive")
		(13 "F.Paste" user "Package Geometry/Pastemask Top")
		(15 "B.Paste" user "Package Geometry/Pastemask Bottom")
		(5 "F.SilkS" user "Ref Des/Silkscreen Top")
		(7 "B.SilkS" user "Ref Des/Silkscreen Bottom")
		(1 "F.Mask" user "Board Geometry/Soldermask Top")
		(3 "B.Mask" user "Board Geometry/Soldermask Bottom")
		(17 "Dwgs.User" user "User.Drawings")
		(19 "Cmts.User" user "User.Comments")
		(21 "Eco1.User" user "User.Eco1")
		(23 "Eco2.User" user "User.Eco2")
		(25 "Edge.Cuts" user "Board Geometry/Outline")
		(27 "Margin" user)
		(31 "F.CrtYd" user "Package Geometry/Place Bound Top")
		(29 "B.CrtYd" user "Package Geometry/Place Bound Bottom")
		(35 "F.Fab" user "Ref Des/Assembly Top")
		(33 "B.Fab" user "Ref Des/Assembly Bottom")
	)
	(footprint ""
		(layer "F.Cu")
		(at 55.245 -33.274)
		(property "Reference" "R644"
			(at 0 0 0)
			(layer "F.SilkS")
			(hide yes)
			(effects
				(font
					(size 1.27 1.27)
				)
			)
		)
		(property "Value" "2R6F-GP"
			(at -0.0508 -4.8514 0)
			(unlocked yes)
			(layer "F.Fab")
			(hide yes)
			(effects
				(font
					(size 1.016 1.016)
					(thickness 0.1524)
				)
			)
		)
		(property "Device Type" "R1206H26"
			(at 0 -6.3754 0)
			(unlocked yes)
			(layer "F.Fab")
			(hide yes)
			(effects
				(font
					(size 1.016 1.016)
					(thickness 0.1524)
				)
			)
		)
		(duplicate_pad_numbers_are_jumpers no)
		(fp_line
			(start -1.016 -2.2352)
			(end 1.016 -2.2352)
			(stroke
				(width 0.1524)
				(type default)
			)
			(layer "F.SilkS")
		)
		(fp_line
			(start -1.016 2.2352)
			(end -1.016 -2.2352)
			(stroke
				(width 0.1524)
				(type default)
			)
			(layer "F.SilkS")
		)
		(fp_line
			(start 1.016 -2.2352)
			(end 1.016 2.2352)
			(stroke
				(width 0.1524)
				(type default)
			)
			(layer "F.SilkS")
		)
		(fp_line
			(start 1.016 2.2352)
			(end -1.016 2.2352)
			(stroke
				(width 0.1524)
				(type default)
			)
			(layer "F.SilkS")
		)
		(fp_rect
			(start -1.0922 2.3114)
			(end 1.0922 -2.3114)
			(stroke
				(width 0)
				(type default)
			)
			(fill no)
			(layer "F.CrtYd")
		)
		(fp_poly
			(pts
				(xy -1.0922 -2.3114) (xy 1.0922 -2.3114) (xy 1.0922 2.3114) (xy -1.0922 2.3114)
			)
			(stroke
				(width 0)
				(type default)
			)
			(fill no)
			(layer "F.Fab")
		)
		(pad "1" smd rect
			(at 0 -1.397)
			(size 1.651 1.27)
			(layers "F.Cu" "F.Mask" "F.Paste")
			(net "P5V_HDD25")
		)
		(pad "2" smd rect
			(at 0 1.397)
			(size 1.651 1.27)
			(layers "F.Cu" "F.Mask" "F.Paste")
			(net "5V_PRE_25")
		)
	)
	(footprint ""
		(layer "F.Cu")
		(at 166.57193 -365.358426)
		(property "Reference" "R1014"
			(at 0 0 0)
			(layer "F.SilkS")
			(hide yes)
			(effects
				(font
					(size 1.27 1.27)
				)
			)
		)
		(property "Value" "4K99R2F-L-GP"
			(at 0.064008 -3.993896 0)
			(unlocked yes)
			(layer "F.Fab")
			(hide yes)
			(effects
				(font
					(size 1.016 1.016)
					(thickness 0.1524)
				)
			)
		)
		(property "Device Type" "R402H16"
			(at 0.064008 -5.517896 0)
			(unlocked yes)
			(layer "F.Fab")
			(hide yes)
			(effects
				(font
					(size 1.016 1.016)
					(thickness 0.1524)
				)
			)
		)
		(duplicate_pad_numbers_are_jumpers no)
		(fp_line
			(start -0.508 -0.9398)
			(end -0.508 0.9398)
			(stroke
				(width 0.1524)
				(type default)
			)
			(layer "F.SilkS")
		)
		(fp_line
			(start 0.508 -0.9398)
			(end -0.508 -0.9398)
			(stroke
				(width 0.1524)
				(type default)
			)
			(layer "F.SilkS")
		)
		(fp_rect
			(start -0.508 0.9398)
			(end 0.508 -0.9398)
			(stroke
				(width 0)
				(type default)
			)
			(fill no)
			(layer "F.CrtYd")
		)
		(fp_rect
			(start -0.508 0.9398)
			(end 0.508 -0.9398)
			(stroke
				(width 0)
				(type default)
			)
			(fill no)
			(layer "F.Fab")
		)
		(pad "1" smd custom
			(at 0 -0.4445)
			(size 0.1397 0.1397)
			(layers "F.Cu" "F.Mask" "F.Paste")
			(net "MB0_CM_UV_R")
			(options
				(clearance outline)
				(anchor circle)
			)
			(primitives
				(gr_poly
					(pts
						(arc
							(start -0.1778 -0.2794)
							(mid -0.249642 -0.249642)
							(end -0.2794 -0.1778)
						)
						(arc
							(start -0.2794 0.1778)
							(mid -0.249642 0.249642)
							(end -0.1778 0.2794)
						)
						(arc
							(start 0.1778 0.2794)
							(mid 0.249642 0.249642)
							(end 0.2794 0.1778)
						)
						(arc
							(start 0.2794 -0.1778)
							(mid 0.249642 -0.249642)
							(end 0.1778 -0.2794)
						)
					)
					(width 0)
					(fill yes)
				)
			)
		)
		(pad "2" smd custom
			(at 0 0.4445)
			(size 0.1397 0.1397)
			(layers "F.Cu" "F.Mask" "F.Paste")
			(net "AGND_CURRENT_MON")
			(options
				(clearance outline)
				(anchor circle)
			)
			(primitives
				(gr_poly
					(pts
						(arc
							(start -0.1778 -0.2794)
							(mid -0.249642 -0.249642)
							(end -0.2794 -0.1778)
						)
						(arc
							(start -0.2794 0.1778)
							(mid -0.249642 0.249642)
							(end -0.1778 0.2794)
						)
						(arc
							(start 0.1778 0.2794)
							(mid 0.249642 0.249642)
							(end 0.2794 0.1778)
						)
						(arc
							(start 0.2794 -0.1778)
							(mid 0.249642 -0.249642)
							(end 0.1778 -0.2794)
						)
					)
					(width 0)
					(fill yes)
				)
			)
		)
	)
	(footprint ""
		(layer "F.Cu")
		(at 178.181 -249.555 180)
		(property "Reference" "Q19"
			(at 0 0 180)
			(layer "F.SilkS")
			(hide yes)
			(effects
				(font
					(size 1.27 1.27)
				)
			)
		)
		(property "Value" "2N7002KDW-GP"
			(at -2.3622 -8.2042 180)
			(unlocked yes)
			(layer "F.Fab")
			(hide yes)
			(effects
				(font
					(size 1.016 1.016)
					(thickness 0.1524)
				)
			)
		)
		(property "Device Type" "SOT-363H44"
			(at -2.3622 -10.1092 180)
			(unlocked yes)
			(layer "F.Fab")
			(hide yes)
			(effects
				(font
					(size 1.016 1.016)
					(thickness 0.1524)
				)
			)
		)
		(duplicate_pad_numbers_are_jumpers no)
		(fp_line
			(start 1.4478 1.7018)
			(end 1.4478 -1.7018)
			(stroke
				(width 0.1524)
				(type default)
			)
			(layer "F.SilkS")
		)
		(fp_line
			(start 1.4478 -1.7018)
			(end -1.4478 -1.7018)
			(stroke
				(width 0.1524)
				(type default)
			)
			(layer "F.SilkS")
		)
		(fp_line
			(start -1.27 1.524)
			(end -1.27 0.6604)
			(stroke
				(width 0.4826)
				(type default)
			)
			(layer "F.SilkS")
		)
		(fp_line
			(start -1.4478 1.7018)
			(end 1.4478 1.7018)
			(stroke
				(width 0.1524)
				(type default)
			)
			(layer "F.SilkS")
		)
		(fp_line
			(start -1.4478 -1.7018)
			(end -1.4478 1.7018)
			(stroke
				(width 0.1524)
				(type default)
			)
			(layer "F.SilkS")
		)
		(fp_poly
			(pts
				(xy -1.524 -1.778) (xy 1.524 -1.778) (xy 1.524 1.778) (xy -1.524 1.778)
			)
			(stroke
				(width 0)
				(type default)
			)
			(fill no)
			(layer "F.CrtYd")
		)
		(fp_poly
			(pts
				(xy -1.524 -1.778) (xy 1.524 -1.778) (xy 1.524 1.778) (xy -1.524 1.778)
			)
			(stroke
				(width 0)
				(type default)
			)
			(fill no)
			(layer "F.Fab")
		)
		(pad "1" smd rect
			(at -0.65024 0.9398 180)
			(size 0.4064 1.016)
			(layers "F.Cu" "F.Mask" "F.Paste")
			(net "GND")
		)
		(pad "2" smd rect
			(at 0 0.9398 180)
			(size 0.4064 1.016)
			(layers "F.Cu" "F.Mask" "F.Paste")
			(net "SW_PWR_R_HDD5")
		)
		(pad "3" smd rect
			(at 0.65024 0.9398 180)
			(size 0.4064 1.016)
			(layers "F.Cu" "F.Mask" "F.Paste")
			(net "SW_HDD_P5")
		)
		(pad "4" smd rect
			(at 0.65024 -0.9398 180)
			(size 0.4064 1.016)
			(layers "F.Cu" "F.Mask" "F.Paste")
			(net "GND")
		)
		(pad "5" smd rect
			(at 0 -0.9398 180)
			(size 0.4064 1.016)
			(layers "F.Cu" "F.Mask" "F.Paste")
			(net "SW_HDD_G5")
		)
		(pad "6" smd rect
			(at -0.65024 -0.9398 180)
			(size 0.4064 1.016)
			(layers "F.Cu" "F.Mask" "F.Paste")
			(net "SW_HDD_R5")
		)
	)
	(footprint ""
		(layer "F.Cu")
		(at 27.794712 -221.75089 -90)
		(property "Reference" "C626"
			(at 0 0 270)
			(layer "F.SilkS")
			(hide yes)
			(effects
				(font
					(size 1.27 1.27)
				)
			)
		)
		(property "Value" "SC2200P50V2KX-2GP"
			(at 1.1811 -2.7051 270)
			(unlocked yes)
			(layer "F.Fab")
			(hide yes)
			(effects
				(font
					(size 1.016 1.016)
					(thickness 0.1524)
				)
			)
		)
		(property "Device Type" "C402H22"
			(at 1.1811 -4.2291 270)
			(unlocked yes)
			(layer "F.Fab")
			(hide yes)
			(effects
				(font
					(size 1.016 1.016)
					(thickness 0.1524)
				)
			)
		)
		(duplicate_pad_numbers_are_jumpers no)
		(fp_rect
			(start -0.4318 0.9525)
			(end 0.4318 -0.9525)
			(stroke
				(width 0)
				(type default)
			)
			(fill no)
			(layer "F.CrtYd")
		)
		(fp_rect
			(start -0.4318 0.9525)
			(end 0.4318 -0.9525)
			(stroke
				(width 0)
				(type default)
			)
			(fill no)
			(layer "F.Fab")
		)
		(pad "1" smd custom
			(at 0 -0.4445 270)
			(size 0.1524 0.1524)
			(layers "F.Cu" "F.Mask" "F.Paste")
			(net "P5V_B_1_LL")
			(options
				(clearance outline)
				(anchor circle)
			)
			(primitives
				(gr_poly
					(pts
						(arc
							(start 0.3048 -0.2032)
							(mid 0.275042 -0.275042)
							(end 0.2032 -0.3048)
						)
						(arc
							(start -0.2032 -0.3048)
							(mid -0.275042 -0.275042)
							(end -0.3048 -0.2032)
						)
						(arc
							(start -0.3048 0.2032)
							(mid -0.275042 0.275042)
							(end -0.2032 0.3048)
						)
						(arc
							(start 0.2032 0.3048)
							(mid 0.275042 0.275042)
							(end 0.3048 0.2032)
						)
					)
					(width 0)
					(fill yes)
				)
			)
		)
		(pad "2" smd custom
			(at 0 0.4445 270)
			(size 0.1524 0.1524)
			(layers "F.Cu" "F.Mask" "F.Paste")
			(net "P5V_B_1_SNB")
			(options
				(clearance outline)
				(anchor circle)
			)
			(primitives
				(gr_poly
					(pts
						(arc
							(start 0.3048 -0.2032)
							(mid 0.275042 -0.275042)
							(end 0.2032 -0.3048)
						)
						(arc
							(start -0.2032 -0.3048)
							(mid -0.275042 -0.275042)
							(end -0.3048 -0.2032)
						)
						(arc
							(start -0.3048 0.2032)
							(mid -0.275042 0.275042)
							(end -0.2032 0.3048)
						)
						(arc
							(start 0.2032 0.3048)
							(mid 0.275042 0.275042)
							(end 0.3048 0.2032)
						)
					)
					(width 0)
					(fill yes)
				)
			)
		)
	)
	(footprint ""
		(layer "F.Cu")
		(at 469.9 -254.508 -90)
		(property "Reference" "R345"
			(at 0 0 270)
			(layer "F.SilkS")
			(hide yes)
			(effects
				(font
					(size 1.27 1.27)
				)
			)
		)
		(property "Value" "300KR2F-GP"
			(at 0.064008 -3.993896 270)
			(unlocked yes)
			(layer "F.Fab")
			(hide yes)
			(effects
				(font
					(size 1.016 1.016)
					(thickness 0.1524)
				)
			)
		)
		(property "Device Type" "R402H16"
			(at 0.064008 -5.517896 270)
			(unlocked yes)
			(layer "F.Fab")
			(hide yes)
			(effects
				(font
					(size 1.016 1.016)
					(thickness 0.1524)
				)
			)
		)
		(duplicate_pad_numbers_are_jumpers no)
		(fp_line
			(start -0.508 -0.9398)
			(end -0.508 0.9398)
			(stroke
				(width 0.1524)
				(type default)
			)
			(layer "F.SilkS")
		)
		(fp_line
			(start 0.508 -0.9398)
			(end -0.508 -0.9398)
			(stroke
				(width 0.1524)
				(type default)
			)
			(layer "F.SilkS")
		)
		(fp_rect
			(start -0.508 0.9398)
			(end 0.508 -0.9398)
			(stroke
				(width 0)
				(type default)
			)
			(fill no)
			(layer "F.CrtYd")
		)
		(fp_rect
			(start -0.508 0.9398)
			(end 0.508 -0.9398)
			(stroke
				(width 0)
				(type default)
			)
			(fill no)
			(layer "F.Fab")
		)
		(pad "1" smd custom
			(at 0 -0.4445 270)
			(size 0.1397 0.1397)
			(layers "F.Cu" "F.Mask" "F.Paste")
			(net "SW_HDD_N11")
			(options
				(clearance outline)
				(anchor circle)
			)
			(primitives
				(gr_poly
					(pts
						(arc
							(start -0.1778 -0.2794)
							(mid -0.249642 -0.249642)
							(end -0.2794 -0.1778)
						)
						(arc
							(start -0.2794 0.1778)
							(mid -0.249642 0.249642)
							(end -0.1778 0.2794)
						)
						(arc
							(start 0.1778 0.2794)
							(mid 0.249642 0.249642)
							(end 0.2794 0.1778)
						)
						(arc
							(start 0.2794 -0.1778)
							(mid 0.249642 -0.249642)
							(end 0.1778 -0.2794)
						)
					)
					(width 0)
					(fill yes)
				)
			)
		)
		(pad "2" smd custom
			(at 0 0.4445 270)
			(size 0.1397 0.1397)
			(layers "F.Cu" "F.Mask" "F.Paste")
			(net "P12V_B")
			(options
				(clearance outline)
				(anchor circle)
			)
			(primitives
				(gr_poly
					(pts
						(arc
							(start -0.1778 -0.2794)
							(mid -0.249642 -0.249642)
							(end -0.2794 -0.1778)
						)
						(arc
							(start -0.2794 0.1778)
							(mid -0.249642 0.249642)
							(end -0.1778 0.2794)
						)
						(arc
							(start 0.1778 0.2794)
							(mid 0.249642 0.249642)
							(end 0.2794 0.1778)
						)
						(arc
							(start 0.2794 -0.1778)
							(mid 0.249642 -0.249642)
							(end 0.1778 -0.2794)
						)
					)
					(width 0)
					(fill yes)
				)
			)
		)
	)
	(footprint ""
		(layer "F.Cu")
		(at 14.859 -246.634 90)
		(property "Reference" "R912"
			(at 0 0 90)
			(layer "F.SilkS")
			(hide yes)
			(effects
				(font
					(size 1.27 1.27)
				)
			)
		)
		(property "Value" "4K7R2J-2-GP"
			(at 0.064008 -3.993896 90)
			(unlocked yes)
			(layer "F.Fab")
			(hide yes)
			(effects
				(font
					(size 1.016 1.016)
					(thickness 0.1524)
				)
			)
		)
		(property "Device Type" "R402H16"
			(at 0.064008 -5.517896 90)
			(unlocked yes)
			(layer "F.Fab")
			(hide yes)
			(effects
				(font
					(size 1.016 1.016)
					(thickness 0.1524)
				)
			)
		)
		(duplicate_pad_numbers_are_jumpers no)
		(fp_line
			(start 0.508 -0.9398)
			(end -0.508 -0.9398)
			(stroke
				(width 0.1524)
				(type default)
			)
			(layer "F.SilkS")
		)
		(fp_line
			(start -0.508 -0.9398)
			(end -0.508 0.9398)
			(stroke
				(width 0.1524)
				(type default)
			)
			(layer "F.SilkS")
		)
		(fp_rect
			(start -0.508 0.9398)
			(end 0.508 -0.9398)
			(stroke
				(width 0)
				(type default)
			)
			(fill no)
			(layer "F.CrtYd")
		)
		(fp_rect
			(start -0.508 0.9398)
			(end 0.508 -0.9398)
			(stroke
				(width 0)
				(type default)
			)
			(fill no)
			(layer "F.Fab")
		)
		(pad "1" smd custom
			(at 0 -0.4445 90)
			(size 0.1397 0.1397)
			(layers "F.Cu" "F.Mask" "F.Paste")
			(net "P12V_B")
			(options
				(clearance outline)
				(anchor circle)
			)
			(primitives
				(gr_poly
					(pts
						(arc
							(start -0.1778 -0.2794)
							(mid -0.249642 -0.249642)
							(end -0.2794 -0.1778)
						)
						(arc
							(start -0.2794 0.1778)
							(mid -0.249642 0.249642)
							(end -0.1778 0.2794)
						)
						(arc
							(start 0.1778 0.2794)
							(mid 0.249642 0.249642)
							(end 0.2794 0.1778)
						)
						(arc
							(start 0.2794 -0.1778)
							(mid 0.249642 -0.249642)
							(end 0.1778 -0.2794)
						)
					)
					(width 0)
					(fill yes)
				)
			)
		)
		(pad "2" smd custom
			(at 0 0.4445 90)
			(size 0.1397 0.1397)
			(layers "F.Cu" "F.Mask" "F.Paste")
			(net "SW_HDD_R0")
			(options
				(clearance outline)
				(anchor circle)
			)
			(primitives
				(gr_poly
					(pts
						(arc
							(start -0.1778 -0.2794)
							(mid -0.249642 -0.249642)
							(end -0.2794 -0.1778)
						)
						(arc
							(start -0.2794 0.1778)
							(mid -0.249642 0.249642)
							(end -0.1778 0.2794)
						)
						(arc
							(start 0.1778 0.2794)
							(mid 0.249642 0.249642)
							(end 0.2794 0.1778)
						)
						(arc
							(start 0.2794 -0.1778)
							(mid 0.249642 -0.249642)
							(end 0.1778 -0.2794)
						)
					)
					(width 0)
					(fill yes)
				)
			)
		)
	)
	(footprint ""
		(layer "F.Cu")
		(at 37.940996 -369.697 180)
		(property "Reference" "R922"
			(at 0 0 180)
			(layer "F.SilkS")
			(hide yes)
			(effects
				(font
					(size 1.27 1.27)
				)
			)
		)
		(property "Value" "4K7R2F-GP"
			(at 0.064008 -3.993896 180)
			(unlocked yes)
			(layer "F.Fab")
			(hide yes)
			(effects
				(font
					(size 1.016 1.016)
					(thickness 0.1524)
				)
			)
		)
		(property "Device Type" "R402H16"
			(at 0.064008 -5.517896 180)
			(unlocked yes)
			(layer "F.Fab")
			(hide yes)
			(effects
				(font
					(size 1.016 1.016)
					(thickness 0.1524)
				)
			)
		)
		(duplicate_pad_numbers_are_jumpers no)
		(fp_line
			(start 0.508 -0.9398)
			(end -0.508 -0.9398)
			(stroke
				(width 0.1524)
				(type default)
			)
			(layer "F.SilkS")
		)
		(fp_line
			(start -0.508 -0.9398)
			(end -0.508 0.9398)
			(stroke
				(width 0.1524)
				(type default)
			)
			(layer "F.SilkS")
		)
		(fp_rect
			(start -0.508 0.9398)
			(end 0.508 -0.9398)
			(stroke
				(width 0)
				(type default)
			)
			(fill no)
			(layer "F.CrtYd")
		)
		(fp_rect
			(start -0.508 0.9398)
			(end 0.508 -0.9398)
			(stroke
				(width 0)
				(type default)
			)
			(fill no)
			(layer "F.Fab")
		)
		(pad "1" smd custom
			(at 0 -0.4445 180)
			(size 0.1397 0.1397)
			(layers "F.Cu" "F.Mask" "F.Paste")
			(net "P12V_IN")
			(options
				(clearance outline)
				(anchor circle)
			)
			(primitives
				(gr_poly
					(pts
						(arc
							(start -0.1778 -0.2794)
							(mid -0.249642 -0.249642)
							(end -0.2794 -0.1778)
						)
						(arc
							(start -0.2794 0.1778)
							(mid -0.249642 0.249642)
							(end -0.1778 0.2794)
						)
						(arc
							(start 0.1778 0.2794)
							(mid 0.249642 0.249642)
							(end 0.2794 0.1778)
						)
						(arc
							(start 0.2794 -0.1778)
							(mid 0.249642 -0.249642)
							(end 0.1778 -0.2794)
						)
					)
					(width 0)
					(fill yes)
				)
			)
		)
		(pad "2" smd custom
			(at 0 0.4445 180)
			(size 0.1397 0.1397)
			(layers "F.Cu" "F.Mask" "F.Paste")
			(net "FAN_0_TACH0")
			(options
				(clearance outline)
				(anchor circle)
			)
			(primitives
				(gr_poly
					(pts
						(arc
							(start -0.1778 -0.2794)
							(mid -0.249642 -0.249642)
							(end -0.2794 -0.1778)
						)
						(arc
							(start -0.2794 0.1778)
							(mid -0.249642 0.249642)
							(end -0.1778 0.2794)
						)
						(arc
							(start 0.1778 0.2794)
							(mid 0.249642 0.249642)
							(end 0.2794 0.1778)
						)
						(arc
							(start 0.2794 -0.1778)
							(mid 0.249642 -0.249642)
							(end 0.1778 -0.2794)
						)
					)
					(width 0)
					(fill yes)
				)
			)
		)
	)
)
